# S9S_MB_2U (Grand Teton) — schematic netlist excerpt (pin names and nets, part order shuffled) for the footprints in the layout excerpt that follows; sources: Cadence DE-HDL packaged netlist, KiCad conversion of 03242023_DA0F0TMBIJ0_F0T_Motherboard_J_brd_V01_OCP.brd

Q108  MOSFET_NCH_DUAL  PJT138K IC  pkg SOT363XD  page 147
  S1  = GND
  G1  = GPU_FPGA_EROT_FATALERR_N
  D2  = GPU_FPGA_EROT_FATALERR_ISO_N
  S2  = GND
  G2  = GPU_FPGA_EROT_FATALERR
  D1  = GPU_FPGA_EROT_FATALERR

(kicad_pcb
	(version 20260206)
	(generator "pcbnew")
	(generator_version "10.0")
	(general
		(thickness 1.6)
		(legacy_teardrops no)
	)
	(paper "A4")
	(title_block
		(title "03242023_DA0F0TMBIJ0_F0T_Motherboard_J_brd_V01_OCP.brd")
		(comment 1 "Grand Teton / footprints 3567-3567 of 6105")
	)
	(layers
		(0 "F.Cu" signal "TOP")
		(4 "In1.Cu" signal "GND")
		(6 "In2.Cu" signal "IN1")
		(8 "In3.Cu" signal "GND1")
		(10 "In4.Cu" signal "IN2")
		(12 "In5.Cu" signal "GND2")
		(14 "In6.Cu" signal "IN3")
		(16 "In7.Cu" signal "GND3")
		(18 "In8.Cu" signal "VCC")
		(20 "In9.Cu" signal "VCC1")
		(22 "In10.Cu" signal "GND4")
		(24 "In11.Cu" signal "IN4")
		(26 "In12.Cu" signal "GND5")
		(28 "In13.Cu" signal "IN5")
		(30 "In14.Cu" signal "GND6")
		(32 "In15.Cu" signal "IN6")
		(34 "In16.Cu" signal "GND7")
		(2 "B.Cu" signal "BOTTOM")
		(9 "F.Adhes" user "F.Adhesive")
		(11 "B.Adhes" user "B.Adhesive")
		(13 "F.Paste" user "Package Geometry/Pastemask Top")
		(15 "B.Paste" user "Package Geometry/Pastemask Bottom")
		(5 "F.SilkS" user "Ref Des/Silkscreen Top")
		(7 "B.SilkS" user "Ref Des/Silkscreen Bottom")
		(1 "F.Mask" user "Board Geometry/Soldermask Top")
		(3 "B.Mask" user "Board Geometry/Soldermask Bottom")
		(17 "Dwgs.User" user "User.Drawings")
		(19 "Cmts.User" user "User.Comments")
		(21 "Eco1.User" user "User.Eco1")
		(23 "Eco2.User" user "User.Eco2")
		(25 "Edge.Cuts" user "Board Geometry/Outline")
		(27 "Margin" user)
		(31 "F.CrtYd" user "Package Geometry/Place Bound Top")
		(29 "B.CrtYd" user "Package Geometry/Place Bound Bottom")
		(35 "F.Fab" user "Ref Des/Assembly Top")
		(33 "B.Fab" user "Ref Des/Assembly Bottom")
	)
	(footprint ""
		(layer "F.Cu")
		(at 96.039686 -423.820336 -90)
		(property "Reference" "Q108"
			(at 6.415278 4.683506 0)
			(unlocked yes)
			(layer "F.SilkS")
			(effects
				(font
					(size 0.7874 0.5842)
					(thickness 0.1524)
				)
				(justify left)
			)
		)
		(property "Value" ""
			(at 0 0 270)
			(layer "F.Fab")
			(effects
				(font
					(size 1.27 1.27)
				)
			)
		)
		(duplicate_pad_numbers_are_jumpers no)
		(fp_line
			(start -1.332738 1.100074)
			(end -1.332738 -1.100074)
			(stroke
				(width 0.1524)
				(type default)
			)
			(layer "F.SilkS")
		)
		(fp_line
			(start 1.332738 1.100074)
			(end -1.332738 1.100074)
			(stroke
				(width 0.1524)
				(type default)
			)
			(layer "F.SilkS")
		)
		(fp_line
			(start 0 -0.541274)
			(end 0.4826 -1.100074)
			(stroke
				(width 0.1524)
				(type default)
			)
			(layer "F.SilkS")
		)
		(fp_line
			(start -1.332738 -1.100074)
			(end -0.4826 -1.100074)
			(stroke
				(width 0.1524)
				(type default)
			)
			(layer "F.SilkS")
		)
		(fp_line
			(start -0.4826 -1.100074)
			(end 0 -0.541274)
			(stroke
				(width 0.1524)
				(type default)
			)
			(layer "F.SilkS")
		)
		(fp_line
			(start 0.4826 -1.100074)
			(end 1.332738 -1.100074)
			(stroke
				(width 0.1524)
				(type default)
			)
			(layer "F.SilkS")
		)
		(fp_line
			(start 1.332738 -1.100074)
			(end 1.332738 1.100074)
			(stroke
				(width 0.1524)
				(type default)
			)
			(layer "F.SilkS")
		)
		(fp_poly
			(pts
				(xy -2.44856 -1.462532) (xy -1.746504 -1.111504) (xy -2.44856 -0.760476)
			)
			(stroke
				(width 0)
				(type default)
			)
			(fill yes)
			(layer "F.SilkS")
		)
		(fp_line
			(start -0.674878 1.100074)
			(end -0.674878 -1.100074)
			(stroke
				(width 0.1)
				(type default)
			)
			(layer "F.Fab")
		)
		(fp_line
			(start 0.674878 1.100074)
			(end -0.674878 1.100074)
			(stroke
				(width 0.1)
				(type default)
			)
			(layer "F.Fab")
		)
		(fp_line
			(start -0.674878 -1.100074)
			(end 0.674878 -1.100074)
			(stroke
				(width 0.1)
				(type default)
			)
			(layer "F.Fab")
		)
		(fp_line
			(start 0.674878 -1.100074)
			(end 0.674878 1.100074)
			(stroke
				(width 0.1)
				(type default)
			)
			(layer "F.Fab")
		)
		(fp_poly
			(pts
				(xy -2.2352 -0.298958) (xy -2.2352 -1.001014) (xy -1.533144 -0.649986)
			)
			(stroke
				(width 0)
				(type default)
			)
			(fill yes)
			(layer "F.Fab")
		)
		(pad "1" smd rect
			(at -0.94996 -0.649986)
			(size 0.4318 0.508)
			(layers "F.Cu" "F.Mask" "F.Paste")
			(net "GND")
		)
		(pad "2" smd rect
			(at -0.94996 0)
			(size 0.4318 0.508)
			(layers "F.Cu" "F.Mask" "F.Paste")
			(net "GPU_FPGA_EROT_FATALERR_N")
		)
		(pad "3" smd rect
			(at -0.94996 0.649986)
			(size 0.4318 0.508)
			(layers "F.Cu" "F.Mask" "F.Paste")
			(net "GPU_FPGA_EROT_FATALERR_ISO_N")
		)
		(pad "4" smd rect
			(at 0.94996 0.649986)
			(size 0.4318 0.508)
			(layers "F.Cu" "F.Mask" "F.Paste")
			(net "GND")
		)
		(pad "5" smd rect
			(at 0.94996 0)
			(size 0.4318 0.508)
			(layers "F.Cu" "F.Mask" "F.Paste")
			(net "GPU_FPGA_EROT_FATALERR")
		)
		(pad "6" smd rect
			(at 0.94996 -0.649986)
			(size 0.4318 0.508)
			(layers "F.Cu" "F.Mask" "F.Paste")
			(net "GPU_FPGA_EROT_FATALERR")
		)
	)
)
